(kicad_pcb
	(version 20260206)
	(generator "pcbnew")
	(generator_version "10.0")
	(general
		(thickness 1.6)
		(legacy_teardrops no)
	)
	(paper "A4")
	(title_block
		(title "v1-chassis-manager — T6M_CM_d_v01_1031_1645.brd")
		(comment 1 "Open CloudServer (Microsoft) / footprint 845 of 2512 (U43), pads 117-128 of 128")
	)
	(layers
		(0 "F.Cu" signal "TOP")
		(4 "In1.Cu" signal "GND1")
		(6 "In2.Cu" signal "IN1")
		(8 "In3.Cu" signal "VCC1")
		(10 "In4.Cu" signal "VCC2")
		(12 "In5.Cu" signal "GND2")
		(14 "In6.Cu" signal "IN2")
		(16 "In7.Cu" signal "IN3")
		(18 "In8.Cu" signal "GND3")
		(2 "B.Cu" signal "BOTTOM")
		(9 "F.Adhes" user "F.Adhesive")
		(11 "B.Adhes" user "B.Adhesive")
		(13 "F.Paste" user "Package Geometry/Pastemask Top")
		(15 "B.Paste" user "Package Geometry/Pastemask Bottom")
		(5 "F.SilkS" user "Ref Des/Silkscreen Top")
		(7 "B.SilkS" user "Ref Des/Silkscreen Bottom")
		(1 "F.Mask" user "Board Geometry/Soldermask Top")
		(3 "B.Mask" user "Board Geometry/Soldermask Bottom")
		(17 "Dwgs.User" user "User.Drawings")
		(19 "Cmts.User" user "User.Comments")
		(21 "Eco1.User" user "User.Eco1")
		(23 "Eco2.User" user "User.Eco2")
		(25 "Edge.Cuts" user "Board Geometry/Outline")
		(27 "Margin" user)
		(31 "F.CrtYd" user "Package Geometry/Place Bound Top")
		(29 "B.CrtYd" user "Package Geometry/Place Bound Bottom")
		(35 "F.Fab" user "Ref Des/Assembly Top")
		(33 "B.Fab" user "Ref Des/Assembly Bottom")
	)
	(footprint ""
		(layer "F.Cu")
		(at 134.01167 -38.63975 -90)
		(property "Reference" "U43"
			(at -10.673334 -1.474216 0)
			(unlocked yes)
			(layer "F.SilkS")
			(effects
				(font
					(size 0.7874 0.5842)
					(thickness 0.1524)
				)
				(justify left)
			)
		)
		(property "Value" ""
			(at 0 0 270)
			(layer "F.Fab")
			(effects
				(font
					(size 1.27 1.27)
				)
			)
		)
		(duplicate_pad_numbers_are_jumpers no)
		(pad "117" smd rect
			(at -0.750062 -11.560048 270)
			(size 0.2794 1.8034)
			(layers "F.Cu" "F.Mask" "F.Paste")
			(net "GND")
		)
		(pad "118" smd rect
			(at -1.249934 -11.560048 270)
			(size 0.2794 1.8034)
			(layers "F.Cu" "F.Mask" "F.Paste")
			(net "Net_512")
		)
		(pad "119" smd rect
			(at -1.75006 -11.560048 270)
			(size 0.2794 1.8034)
			(layers "F.Cu" "F.Mask" "F.Paste")
			(net "UART_RI_P1_N")
		)
		(pad "120" smd rect
			(at -2.249932 -11.560048 270)
			(size 0.2794 1.8034)
			(layers "F.Cu" "F.Mask" "F.Paste")
			(net "UART_CTS_P1_N")
		)
		(pad "121" smd rect
			(at -2.750058 -11.560048 270)
			(size 0.2794 1.8034)
			(layers "F.Cu" "F.Mask" "F.Paste")
			(net "UART_DTR_P1_N")
		)
		(pad "122" smd rect
			(at -3.24993 -11.560048 270)
			(size 0.2794 1.8034)
			(layers "F.Cu" "F.Mask" "F.Paste")
			(net "UART_RTS_P1_N")
		)
		(pad "123" smd rect
			(at -3.750056 -11.560048 270)
			(size 0.2794 1.8034)
			(layers "F.Cu" "F.Mask" "F.Paste")
			(net "UART_DSR_P1_N")
		)
		(pad "124" smd rect
			(at -4.249928 -11.560048 270)
			(size 0.2794 1.8034)
			(layers "F.Cu" "F.Mask" "F.Paste")
			(net "UART_TX_P1")
		)
		(pad "125" smd rect
			(at -4.750054 -11.560048 270)
			(size 0.2794 1.8034)
			(layers "F.Cu" "F.Mask" "F.Paste")
			(net "UART_RX_P1")
		)
		(pad "126" smd rect
			(at -5.249926 -11.560048 270)
			(size 0.2794 1.8034)
			(layers "F.Cu" "F.Mask" "F.Paste")
			(net "Net_513")
		)
		(pad "127" smd rect
			(at -5.750052 -11.560048 270)
			(size 0.2794 1.8034)
			(layers "F.Cu" "F.Mask" "F.Paste")
			(net "UART_RI_P2_N")
		)
		(pad "128" smd rect
			(at -6.249924 -11.560048 270)
			(size 0.2794 1.8034)
			(layers "F.Cu" "F.Mask" "F.Paste")
			(net "UART_CTS_P2_N")
		)
	)
)
